(kicad_pcb
	(version 20260206)
	(generator "pcbnew")
	(generator_version "10.0")
	(general
		(thickness 1.6)
		(legacy_teardrops no)
	)
	(paper "A4")
	(title_block
		(title "03242023_DA0F0TMBIJ0_F0T_Motherboard_J_brd_V01_OCP.brd")
		(comment 1 "Grand Teton / footprints 2537-2538 of 6105")
	)
	(layers
		(0 "F.Cu" signal "TOP")
		(4 "In1.Cu" signal "GND")
		(6 "In2.Cu" signal "IN1")
		(8 "In3.Cu" signal "GND1")
		(10 "In4.Cu" signal "IN2")
		(12 "In5.Cu" signal "GND2")
		(14 "In6.Cu" signal "IN3")
		(16 "In7.Cu" signal "GND3")
		(18 "In8.Cu" signal "VCC")
		(20 "In9.Cu" signal "VCC1")
		(22 "In10.Cu" signal "GND4")
		(24 "In11.Cu" signal "IN4")
		(26 "In12.Cu" signal "GND5")
		(28 "In13.Cu" signal "IN5")
		(30 "In14.Cu" signal "GND6")
		(32 "In15.Cu" signal "IN6")
		(34 "In16.Cu" signal "GND7")
		(2 "B.Cu" signal "BOTTOM")
		(9 "F.Adhes" user "F.Adhesive")
		(11 "B.Adhes" user "B.Adhesive")
		(13 "F.Paste" user "Package Geometry/Pastemask Top")
		(15 "B.Paste" user "Package Geometry/Pastemask Bottom")
		(5 "F.SilkS" user "Ref Des/Silkscreen Top")
		(7 "B.SilkS" user "Ref Des/Silkscreen Bottom")
		(1 "F.Mask" user "Board Geometry/Soldermask Top")
		(3 "B.Mask" user "Board Geometry/Soldermask Bottom")
		(17 "Dwgs.User" user "User.Drawings")
		(19 "Cmts.User" user "User.Comments")
		(21 "Eco1.User" user "User.Eco1")
		(23 "Eco2.User" user "User.Eco2")
		(25 "Edge.Cuts" user "Board Geometry/Outline")
		(27 "Margin" user)
		(31 "F.CrtYd" user "Package Geometry/Place Bound Top")
		(29 "B.CrtYd" user "Package Geometry/Place Bound Bottom")
		(35 "F.Fab" user "Ref Des/Assembly Top")
		(33 "B.Fab" user "Ref Des/Assembly Bottom")
	)
	(footprint ""
		(layer "F.Cu")
		(at 23.241 -397.025876 -90)
		(property "Reference" "R3283"
			(at 0 0 270)
			(layer "F.SilkS")
			(hide yes)
			(effects
				(font
					(size 1.27 1.27)
				)
			)
		)
		(property "Value" ""
			(at 0 0 270)
			(layer "F.Fab")
			(effects
				(font
					(size 1.27 1.27)
				)
			)
		)
		(duplicate_pad_numbers_are_jumpers no)
		(fp_line
			(start -0.7874 0.4064)
			(end -0.7874 -0.4064)
			(stroke
				(width 0.1524)
				(type default)
			)
			(layer "F.SilkS")
		)
		(fp_line
			(start 0.7874 0.4064)
			(end -0.7874 0.4064)
			(stroke
				(width 0.1524)
				(type default)
			)
			(layer "F.SilkS")
		)
		(fp_line
			(start -0.7874 -0.4064)
			(end 0.7874 -0.4064)
			(stroke
				(width 0.1524)
				(type default)
			)
			(layer "F.SilkS")
		)
		(fp_line
			(start 0.7874 -0.4064)
			(end 0.7874 0.4064)
			(stroke
				(width 0.1524)
				(type default)
			)
			(layer "F.SilkS")
		)
		(fp_line
			(start -0.67945 0.3048)
			(end -0.67945 -0.305054)
			(stroke
				(width 0.1)
				(type default)
			)
			(layer "F.Fab")
		)
		(fp_line
			(start -0.12065 0.3048)
			(end -0.67945 0.3048)
			(stroke
				(width 0.1)
				(type default)
			)
			(layer "F.Fab")
		)
		(fp_line
			(start 0.120396 0.3048)
			(end 0.120396 0.2794)
			(stroke
				(width 0.1)
				(type default)
			)
			(layer "F.Fab")
		)
		(fp_line
			(start 0.67945 0.3048)
			(end 0.120396 0.3048)
			(stroke
				(width 0.1)
				(type default)
			)
			(layer "F.Fab")
		)
		(fp_line
			(start -0.12065 0.2794)
			(end -0.12065 0.3048)
			(stroke
				(width 0.1)
				(type default)
			)
			(layer "F.Fab")
		)
		(fp_line
			(start 0.120396 0.2794)
			(end -0.12065 0.2794)
			(stroke
				(width 0.1)
				(type default)
			)
			(layer "F.Fab")
		)
		(fp_line
			(start -0.12065 -0.2794)
			(end 0.12065 -0.2794)
			(stroke
				(width 0.1)
				(type default)
			)
			(layer "F.Fab")
		)
		(fp_line
			(start 0.12065 -0.2794)
			(end 0.12065 -0.3048)
			(stroke
				(width 0.1)
				(type default)
			)
			(layer "F.Fab")
		)
		(fp_line
			(start 0.12065 -0.3048)
			(end 0.67945 -0.3048)
			(stroke
				(width 0.1)
				(type default)
			)
			(layer "F.Fab")
		)
		(fp_line
			(start 0.67945 -0.3048)
			(end 0.67945 0.3048)
			(stroke
				(width 0.1)
				(type default)
			)
			(layer "F.Fab")
		)
		(fp_line
			(start -0.67945 -0.305054)
			(end -0.12065 -0.305054)
			(stroke
				(width 0.1)
				(type default)
			)
			(layer "F.Fab")
		)
		(fp_line
			(start -0.12065 -0.305054)
			(end -0.12065 -0.2794)
			(stroke
				(width 0.1)
				(type default)
			)
			(layer "F.Fab")
		)
		(pad "1" smd circle
			(at -0.40005 0 270)
			(size 0 0)
			(layers "F.Cu" "F.Mask" "F.Paste")
			(net "P3V3_AUX")
		)
		(pad "2" smd circle
			(at 0.40005 0 270)
			(size 0 0)
			(layers "F.Cu" "F.Mask" "F.Paste")
			(net "FM_P2E_EQB0")
		)
	)
	(footprint ""
		(layer "F.Cu")
		(at 437.10733 -16.248126 -90)
		(property "Reference" "R418"
			(at 0 0 270)
			(layer "F.SilkS")
			(hide yes)
			(effects
				(font
					(size 1.27 1.27)
				)
			)
		)
		(property "Value" ""
			(at 0 0 270)
			(layer "F.Fab")
			(effects
				(font
					(size 1.27 1.27)
				)
			)
		)
		(duplicate_pad_numbers_are_jumpers no)
		(fp_line
			(start -0.7874 0.4064)
			(end -0.7874 -0.4064)
			(stroke
				(width 0.1524)
				(type default)
			)
			(layer "F.SilkS")
		)
		(fp_line
			(start 0.7874 0.4064)
			(end -0.7874 0.4064)
			(stroke
				(width 0.1524)
				(type default)
			)
			(layer "F.SilkS")
		)
		(fp_line
			(start -0.7874 -0.4064)
			(end 0.7874 -0.4064)
			(stroke
				(width 0.1524)
				(type default)
			)
			(layer "F.SilkS")
		)
		(fp_line
			(start 0.7874 -0.4064)
			(end 0.7874 0.4064)
			(stroke
				(width 0.1524)
				(type default)
			)
			(layer "F.SilkS")
		)
		(fp_line
			(start -0.67945 0.3048)
			(end -0.67945 -0.305054)
			(stroke
				(width 0.1)
				(type default)
			)
			(layer "F.Fab")
		)
		(fp_line
			(start -0.12065 0.3048)
			(end -0.67945 0.3048)
			(stroke
				(width 0.1)
				(type default)
			)
			(layer "F.Fab")
		)
		(fp_line
			(start 0.120396 0.3048)
			(end 0.120396 0.2794)
			(stroke
				(width 0.1)
				(type default)
			)
			(layer "F.Fab")
		)
		(fp_line
			(start 0.67945 0.3048)
			(end 0.120396 0.3048)
			(stroke
				(width 0.1)
				(type default)
			)
			(layer "F.Fab")
		)
		(fp_line
			(start -0.12065 0.2794)
			(end -0.12065 0.3048)
			(stroke
				(width 0.1)
				(type default)
			)
			(layer "F.Fab")
		)
		(fp_line
			(start 0.120396 0.2794)
			(end -0.12065 0.2794)
			(stroke
				(width 0.1)
				(type default)
			)
			(layer "F.Fab")
		)
		(fp_line
			(start -0.12065 -0.2794)
			(end 0.12065 -0.2794)
			(stroke
				(width 0.1)
				(type default)
			)
			(layer "F.Fab")
		)
		(fp_line
			(start 0.12065 -0.2794)
			(end 0.12065 -0.3048)
			(stroke
				(width 0.1)
				(type default)
			)
			(layer "F.Fab")
		)
		(fp_line
			(start 0.12065 -0.3048)
			(end 0.67945 -0.3048)
			(stroke
				(width 0.1)
				(type default)
			)
			(layer "F.Fab")
		)
		(fp_line
			(start 0.67945 -0.3048)
			(end 0.67945 0.3048)
			(stroke
				(width 0.1)
				(type default)
			)
			(layer "F.Fab")
		)
		(fp_line
			(start -0.67945 -0.305054)
			(end -0.12065 -0.305054)
			(stroke
				(width 0.1)
				(type default)
			)
			(layer "F.Fab")
		)
		(fp_line
			(start -0.12065 -0.305054)
			(end -0.12065 -0.2794)
			(stroke
				(width 0.1)
				(type default)
			)
			(layer "F.Fab")
		)
		(pad "1" smd circle
			(at -0.40005 0 270)
			(size 0 0)
			(layers "F.Cu" "F.Mask" "F.Paste")
			(net "OCP_SFF_ISO_BIF2_EN")
		)
		(pad "2" smd circle
			(at 0.40005 0 270)
			(size 0 0)
			(layers "F.Cu" "F.Mask" "F.Paste")
			(net "OCP_SFF_BIF2_R_N")
		)
	)
)
